FILE_TYPE = MACRO_DRAWING;
SET COLOR_WIRE YELLOW;
SET COLOR_PROP ORANGE;
SET COLOR_DOT WHITE;
SET COLOR_ARC YELLOW;
SET COLOR_BODY GREEN;
SET COLOR_NOTE PURPLE;
SET PROP_DISPLAY VALUE;
SET PAGE_NUMBER P53;
SET PATH_NUMBER P73;
FORCEADD UNIVERSAL_GND..1
(-1650 775);
FORCEPROP 3 LASTPIN (-1650 825) SIG_NAME GND\g
J 0
(-1640 835);
DISPLAY 0.659574 (-1640 835);
PAINT MONO (-1640 835);
DISPLAY INVISIBLE (-1640 835);
FORCEPROP 2 LAST CDS_LIB logical_power
J 0
(-1650 775);
DISPLAY INVISIBLE (-1650 775);
FORCEPROP 1 LAST HDL_POWER GND
J 1
(-1625 700);
DISPLAY 0.702128 (-1625 700);
PAINT GREEN (-1625 700);
DISPLAY INVISIBLE (-1625 700);
FORCEPROP 1 LAST PATH I10
J 0
(-1575 775);
DISPLAY 0.872340 (-1575 775);
PAINT AQUA (-1575 775);
DISPLAY INVISIBLE (-1575 775);
FORCEADD UNIVERSAL_GND..1
(-100 -400);
FORCEPROP 3 LASTPIN (-100 -350) SIG_NAME GND\g
J 0
(-90 -340);
DISPLAY 0.659574 (-90 -340);
PAINT MONO (-90 -340);
DISPLAY INVISIBLE (-90 -340);
FORCEPROP 2 LAST CDS_LIB logical_power
J 0
(-100 -400);
DISPLAY INVISIBLE (-100 -400);
FORCEPROP 1 LAST HDL_POWER GND
J 1
(-75 -475);
DISPLAY 0.702128 (-75 -475);
PAINT GREEN (-75 -475);
DISPLAY INVISIBLE (-75 -475);
FORCEPROP 1 LAST PATH I16
J 0
(-25 -400);
DISPLAY 0.872340 (-25 -400);
PAINT AQUA (-25 -400);
DISPLAY INVISIBLE (-25 -400);
FORCEADD VCCAUX15..1
(-1650 1525);
FORCEPROP 3 LASTPIN (-1650 1475) SIG_NAME P5V_AUX\g
J 0
(-1640 1485);
DISPLAY 0.659574 (-1640 1485);
PAINT MONO (-1640 1485);
DISPLAY INVISIBLE (-1640 1485);
FORCEPROP 1 LAST HDL_POWER P5V_AUX
J 1
(-1650 1575);
DISPLAY 0.702128 (-1650 1575);
PAINT GREEN (-1650 1575);
FORCEPROP 2 LAST CDS_LIB logical_power
J 0
(-1650 1525);
DISPLAY INVISIBLE (-1650 1525);
FORCEPROP 1 LAST PATH I2
J 0
(-1600 1550);
DISPLAY 0.872340 (-1600 1550);
PAINT AQUA (-1600 1550);
DISPLAY INVISIBLE (-1600 1550);
FORCEADD UNIVERSAL_GND..1
(1250 -175);
FORCEPROP 3 LASTPIN (1250 -125) SIG_NAME GND\g
J 0
(1260 -115);
DISPLAY 0.659574 (1260 -115);
PAINT MONO (1260 -115);
DISPLAY INVISIBLE (1260 -115);
FORCEPROP 2 LAST CDS_LIB logical_power
J 0
(1250 -175);
DISPLAY INVISIBLE (1250 -175);
FORCEPROP 1 LAST HDL_POWER GND
J 1
(1275 -250);
DISPLAY 0.702128 (1275 -250);
PAINT GREEN (1275 -250);
DISPLAY INVISIBLE (1275 -250);
FORCEPROP 1 LAST PATH I26
J 0
(1325 -175);
DISPLAY 0.872340 (1325 -175);
PAINT AQUA (1325 -175);
DISPLAY INVISIBLE (1325 -175);
FORCEADD VCCAUX15..1
(2400 650);
FORCEPROP 3 LASTPIN (2400 600) SIG_NAME P2V5_AUX\g
J 0
(2410 610);
DISPLAY 0.659574 (2410 610);
PAINT MONO (2410 610);
DISPLAY INVISIBLE (2410 610);
FORCEPROP 1 LAST HDL_POWER P2V5_AUX
J 1
(2400 700);
DISPLAY 0.702128 (2400 700);
PAINT GREEN (2400 700);
FORCEPROP 2 LAST CDS_LIB logical_power
J 0
(2400 650);
DISPLAY INVISIBLE (2400 650);
FORCEPROP 1 LAST PATH I29
J 0
(2450 675);
DISPLAY 0.872340 (2450 675);
PAINT AQUA (2450 675);
DISPLAY INVISIBLE (2450 675);
FORCEADD VCCAUX15..1
(-1375 275);
FORCEPROP 3 LASTPIN (-1375 225) SIG_NAME P3V3_AUX\g
J 0
(-1365 235);
DISPLAY 0.659574 (-1365 235);
PAINT MONO (-1365 235);
DISPLAY INVISIBLE (-1365 235);
FORCEPROP 1 LAST HDL_POWER P3V3_AUX
J 1
(-1375 325);
DISPLAY 0.702128 (-1375 325);
PAINT GREEN (-1375 325);
FORCEPROP 2 LAST CDS_LIB logical_power
J 0
(-1375 275);
DISPLAY INVISIBLE (-1375 275);
FORCEPROP 1 LAST PATH I45
J 0
(-1325 300);
DISPLAY 0.872340 (-1325 300);
PAINT AQUA (-1325 300);
DISPLAY INVISIBLE (-1325 300);
FORCEADD VCCAUX15..1
(400 1700);
FORCEPROP 3 LASTPIN (400 1650) SIG_NAME P3V3_AUX\g
J 0
(410 1660);
DISPLAY 0.659574 (410 1660);
PAINT MONO (410 1660);
DISPLAY INVISIBLE (410 1660);
FORCEPROP 1 LAST HDL_POWER P3V3_AUX
J 1
(400 1750);
DISPLAY 0.702128 (400 1750);
PAINT GREEN (400 1750);
FORCEPROP 2 LAST CDS_LIB logical_power
J 0
(400 1700);
DISPLAY INVISIBLE (400 1700);
FORCEPROP 1 LAST PATH I48
J 0
(450 1725);
DISPLAY 0.872340 (450 1725);
PAINT AQUA (450 1725);
DISPLAY INVISIBLE (450 1725);
FORCEADD UNIVERSAL_GND..1
(400 950);
FORCEPROP 3 LASTPIN (400 1000) SIG_NAME GND\g
J 0
(410 1010);
DISPLAY 0.659574 (410 1010);
PAINT MONO (410 1010);
DISPLAY INVISIBLE (410 1010);
FORCEPROP 2 LAST CDS_LIB logical_power
J 0
(400 950);
DISPLAY INVISIBLE (400 950);
FORCEPROP 1 LAST HDL_POWER GND
J 1
(425 875);
DISPLAY 0.702128 (425 875);
PAINT GREEN (425 875);
DISPLAY INVISIBLE (425 875);
FORCEPROP 1 LAST PATH I50
J 0
(475 950);
DISPLAY 0.872340 (475 950);
PAINT AQUA (475 950);
DISPLAY INVISIBLE (475 950);
FORCEADD OFFPAGE..2
R 2
(-4000 -125);
FORCEPROP 2 LAST $XR0 35 
J 0
(-4254 -125);
DISPLAY 0.638298 (-4254 -125);
PAINT MONO (-4254 -125);
FORCEPROP 2 LAST CDS_LIB standard
J 0
(-4000 -125);
DISPLAY INVISIBLE (-4000 -125);
FORCEPROP 1 LAST OFFPAGE TRUE
J 2
(-4325 -250);
DISPLAY 0.872340 (-4325 -250);
PAINT GREEN (-4325 -250);
DISPLAY INVISIBLE (-4325 -250);
FORCEPROP 1 LAST COMMENT_BODY TRUE
J 2
(-3955 -220);
DISPLAY 0.872340 (-3955 -220);
PAINT PEACH (-3955 -220);
DISPLAY INVISIBLE (-3955 -220);
FORCEPROP 2 LAST PATH I54
J 0
(-3950 -50);
DISPLAY 1.021277 (-3950 -50);
DISPLAY INVISIBLE (-3950 -50);
FORCEADD Q_RES..1
(-2525 -125);
FORCEPROP 1 LAST VALUE 0
J 2
(-2300 -125);
DISPLAY 0.510638 (-2300 -125);
PAINT SKYBLUE (-2300 -125);
FORCEPROP 1 LAST MATERIAL CHIP
J 0
(-2275 -125);
DISPLAY 0.510638 (-2275 -125);
PAINT SKYBLUE (-2275 -125);
FORCEPROP 1 LAST PACK_TYPE 0402LF
J 0
(-2600 -175);
DISPLAY 0.510638 (-2600 -175);
PAINT SKYBLUE (-2600 -175);
FORCEPROP 1 LAST PART_NUMBER CS00002JB13
J 0
(-2625 -75);
DISPLAY 0.510638 (-2625 -75);
PAINT WHITE (-2625 -75);
FORCEPROP 2 LAST CDS_LIB pure_quanta
J 0
(-2525 -125);
DISPLAY INVISIBLE (-2525 -125);
FORCEPROP 1 LAST PATH I58
J 0
(-2575 25);
DISPLAY 0.978723 (-2575 25);
PAINT WHITE (-2575 25);
DISPLAY INVISIBLE (-2575 25);
FORCEPROP 1 LAST WATTAGE 1/16W
J 2
(-2550 -275);
DISPLAY 0.510638 (-2550 -275);
PAINT SKYBLUE (-2550 -275);
DISPLAY INVISIBLE (-2550 -275);
FORCEPROP 1 LAST TOLERANCE 5%
J 0
(-2525 -225);
DISPLAY 0.510638 (-2525 -225);
PAINT SKYBLUE (-2525 -225);
DISPLAY INVISIBLE (-2525 -225);
FORCEPROP 1 LAST LOCATION R35
J 0
(-2775 -125);
DISPLAY 0.702128 (-2775 -125);
PAINT YELLOW (-2775 -125);
FORCEPROP 1 LASTPIN (-2625 -125) $PN 1
J 0
(-2613 -113);
DISPLAY 0.808511 (-2613 -113);
PAINT WHITE (-2613 -113);
FORCEPROP 1 LASTPIN (-2425 -125) $PN 2
J 0
(-2463 -113);
DISPLAY 0.808511 (-2463 -113);
PAINT WHITE (-2463 -113);
FORCEPROP 2 LAST $SEC 1
J 0
(-2650 100);
DISPLAY 0.680851 (-2650 100);
PAINT MONO (-2650 100);
DISPLAY INVISIBLE (-2650 100);
FORCEPROP 0 LAST CDS_SEC 1
J 0
(-2650 100);
DISPLAY 0.680851 (-2650 100);
PAINT MONO (-2650 100);
DISPLAY INVISIBLE (-2650 100);
FORCEADD RT9059GQW..1
(-650 375);
FORCEPROP 2 LAST PART_TYPE SMLF
J 0
(-875 1175);
DISPLAY 0.510638 (-875 1175);
PAINT SKYBLUE (-875 1175);
FORCEPROP 2 LAST VALUE RT9059GQW
J 0
(-875 1125);
DISPLAY 0.510638 (-875 1125);
PAINT SKYBLUE (-875 1125);
FORCEPROP 1 LAST MATERIAL IC
J 0
(-899 940);
DISPLAY 0.510638 (-899 940);
PAINT SKYBLUE (-899 940);
FORCEPROP 1 LAST PART_NUMBER AL009059000
J 0
(-899 1010);
DISPLAY 0.510638 (-899 1010);
PAINT WHITE (-899 1010);
FORCEPROP 1 LAST PIN_NAMES_ROTATE True
J 0
(-650 375);
DISPLAY 0.723404 (-650 375);
PAINT GREEN (-650 375);
DISPLAY INVISIBLE (-650 375);
FORCEPROP 1 LAST CDS_LMAN_SYM_OUTLINE -250,550,250,-550
J 0
(-650 375);
DISPLAY 0.468085 (-650 375);
PAINT GREEN (-650 375);
DISPLAY INVISIBLE (-650 375);
FORCEPROP 2 LAST CDS_LIB pure_quanta
J 0
(-650 375);
DISPLAY INVISIBLE (-650 375);
FORCEPROP 1 LAST PATH I60
J 2
(-400 -175);
DISPLAY 0.723404 (-400 -175);
PAINT GREEN (-400 -175);
DISPLAY INVISIBLE (-400 -175);
FORCEPROP 1 LAST LOCATION U39
J 0
(-899 1070);
DISPLAY 0.702128 (-899 1070);
PAINT AQUA (-899 1070);
FORCEPROP 0 LASTPIN (-250 75) $PN 4
J 0
(-240 85);
DISPLAY 0.680851 (-240 85);
PAINT MONO (-240 85);
FORCEPROP 0 LASTPIN (-1050 425) $PN 6
J 2
(-1060 435);
DISPLAY 0.680851 (-1060 435);
PAINT MONO (-1060 435);
FORCEPROP 0 LASTPIN (-250 -125) $PN TH
J 0
(-240 -115);
DISPLAY 0.680851 (-240 -115);
PAINT MONO (-240 -115);
FORCEPROP 0 LASTPIN (-1050 -125) $PN 5
J 2
(-1060 -115);
DISPLAY 0.680851 (-1060 -115);
PAINT MONO (-1060 -115);
FORCEPROP 0 LASTPIN (-1050 875) $PN 10
J 2
(-1060 885);
DISPLAY 0.680851 (-1060 885);
PAINT MONO (-1060 885);
FORCEPROP 0 LASTPIN (-250 875) $PN 7
J 0
(-240 885);
DISPLAY 0.680851 (-240 885);
PAINT MONO (-240 885);
FORCEPROP 0 LASTPIN (-250 825) $PN 8
J 0
(-240 835);
DISPLAY 0.680851 (-240 835);
PAINT MONO (-240 835);
FORCEPROP 0 LASTPIN (-250 775) $PN 9
J 0
(-240 785);
DISPLAY 0.680851 (-240 785);
PAINT MONO (-240 785);
FORCEPROP 0 LASTPIN (-250 475) $PN 1
J 0
(-240 485);
DISPLAY 0.680851 (-240 485);
PAINT MONO (-240 485);
FORCEPROP 0 LASTPIN (-250 425) $PN 2
J 0
(-240 435);
DISPLAY 0.680851 (-240 435);
PAINT MONO (-240 435);
FORCEPROP 0 LASTPIN (-250 375) $PN 3
J 0
(-240 385);
DISPLAY 0.680851 (-240 385);
PAINT MONO (-240 385);
FORCEPROP 0 LAST $SEC 1
J 0
(-875 1200);
DISPLAY 0.680851 (-875 1200);
PAINT MONO (-875 1200);
DISPLAY INVISIBLE (-875 1200);
FORCEPROP 0 LAST CDS_SEC 1
J 0
(-875 1200);
DISPLAY 1.021277 (-875 1200);
DISPLAY INVISIBLE (-875 1200);
FORCEADD Q_RES..2
(325 -175);
FORCEPROP 1 LAST VALUE 12K
J 0
(370 -100);
DISPLAY 0.510638 (370 -100);
PAINT SKYBLUE (370 -100);
FORCEPROP 1 LAST TOLERANCE 1%
J 0
(370 -150);
DISPLAY 0.510638 (370 -150);
PAINT SKYBLUE (370 -150);
FORCEPROP 1 LAST WATTAGE 1/16W
J 0
(365 -200);
DISPLAY 0.510638 (365 -200);
PAINT SKYBLUE (365 -200);
FORCEPROP 1 LAST MATERIAL CHIP
J 0
(365 -250);
DISPLAY 0.510638 (365 -250);
PAINT SKYBLUE (365 -250);
FORCEPROP 1 LAST PART_NUMBER CS31202FB04
J 0
(365 -300);
DISPLAY 0.510638 (365 -300);
PAINT WHITE (365 -300);
FORCEPROP 1 LAST PACK_TYPE 0402LF
J 0
(365 -350);
DISPLAY 0.510638 (365 -350);
PAINT SKYBLUE (365 -350);
FORCEPROP 2 LAST CDS_LIB pure_quanta
J 0
(325 -175);
DISPLAY INVISIBLE (325 -175);
FORCEPROP 1 LAST PATH I61
J 0
(375 0);
DISPLAY 0.978723 (375 0);
PAINT WHITE (375 0);
DISPLAY INVISIBLE (375 0);
FORCEPROP 1 LAST LOCATION R830
J 0
(370 -50);
DISPLAY 0.702128 (370 -50);
PAINT YELLOW (370 -50);
FORCEPROP 0 LAST $SEC 1
J 0
(375 0);
DISPLAY 0.680851 (375 0);
PAINT MONO (375 0);
DISPLAY INVISIBLE (375 0);
FORCEPROP 0 LAST CDS_SEC 1
J 0
(375 0);
DISPLAY 1.021277 (375 0);
DISPLAY INVISIBLE (375 0);
FORCEPROP 1 LASTPIN (325 -75) $PN 1
J 0
(330 -113);
DISPLAY 0.808511 (330 -113);
PAINT WHITE (330 -113);
DISPLAY INVISIBLE (330 -113);
FORCEPROP 1 LASTPIN (325 -275) $PN 2
J 0
(330 -265);
DISPLAY 0.808511 (330 -265);
PAINT WHITE (330 -265);
DISPLAY INVISIBLE (330 -265);
FORCEADD Q_RES..2
(325 250);
FORCEPROP 1 LAST VALUE 25.5K
J 0
(370 325);
DISPLAY 0.510638 (370 325);
PAINT SKYBLUE (370 325);
FORCEPROP 1 LAST TOLERANCE 1%
J 0
(370 275);
DISPLAY 0.510638 (370 275);
PAINT SKYBLUE (370 275);
FORCEPROP 1 LAST PACK_TYPE 0402LF
J 0
(365 75);
DISPLAY 0.510638 (365 75);
PAINT SKYBLUE (365 75);
FORCEPROP 1 LAST WATTAGE 1/16W
J 0
(365 225);
DISPLAY 0.510638 (365 225);
PAINT SKYBLUE (365 225);
FORCEPROP 1 LAST MATERIAL CHIP
J 0
(365 175);
DISPLAY 0.510638 (365 175);
PAINT SKYBLUE (365 175);
FORCEPROP 1 LAST PART_NUMBER CS32552FB06
J 0
(365 125);
DISPLAY 0.510638 (365 125);
PAINT WHITE (365 125);
FORCEPROP 2 LAST CDS_LIB pure_quanta
J 0
(325 250);
DISPLAY INVISIBLE (325 250);
FORCEPROP 1 LAST PATH I62
J 0
(375 425);
DISPLAY 0.978723 (375 425);
PAINT WHITE (375 425);
DISPLAY INVISIBLE (375 425);
FORCEPROP 1 LAST LOCATION R829
J 0
(370 375);
DISPLAY 0.702128 (370 375);
PAINT YELLOW (370 375);
FORCEPROP 0 LAST $SEC 1
J 0
(375 425);
DISPLAY 0.680851 (375 425);
PAINT MONO (375 425);
DISPLAY INVISIBLE (375 425);
FORCEPROP 0 LAST CDS_SEC 1
J 0
(375 425);
DISPLAY 1.021277 (375 425);
DISPLAY INVISIBLE (375 425);
FORCEPROP 1 LASTPIN (325 350) $PN 1
J 0
(330 312);
DISPLAY 0.808511 (330 312);
PAINT WHITE (330 312);
DISPLAY INVISIBLE (330 312);
FORCEPROP 1 LASTPIN (325 150) $PN 2
J 0
(330 160);
DISPLAY 0.808511 (330 160);
PAINT WHITE (330 160);
DISPLAY INVISIBLE (330 160);
FORCEADD UNIVERSAL_GND..1
(-2025 -525);
FORCEPROP 3 LASTPIN (-2025 -475) SIG_NAME GND\g
J 0
(-2015 -465);
DISPLAY 0.659574 (-2015 -465);
PAINT MONO (-2015 -465);
DISPLAY INVISIBLE (-2015 -465);
FORCEPROP 2 LAST CDS_LIB logical_power
J 0
(-2025 -525);
DISPLAY INVISIBLE (-2025 -525);
FORCEPROP 1 LAST HDL_POWER GND
J 1
(-2000 -600);
DISPLAY 0.702128 (-2000 -600);
PAINT GREEN (-2000 -600);
DISPLAY INVISIBLE (-2000 -600);
FORCEPROP 1 LAST PATH I63
J 0
(-1950 -525);
DISPLAY 0.872340 (-1950 -525);
PAINT AQUA (-1950 -525);
DISPLAY INVISIBLE (-1950 -525);
FORCEADD Q_CAP..1
(-2025 -325);
FORCEPROP 1 LAST PART_NUMBER CH30106KB19
J 0
(-1975 -475);
DISPLAY 0.978723 (-1975 -475);
FORCEPROP 1 LAST PACK_TYPE C0402
J 0
(-1975 -525);
DISPLAY 0.978723 (-1975 -525);
FORCEPROP 1 LAST TOLERANCE 10%
J 0
(-1975 -375);
DISPLAY 0.978723 (-1975 -375);
FORCEPROP 1 LAST VOLTAGE 50V
J 0
(-1975 -325);
DISPLAY 0.978723 (-1975 -325);
FORCEPROP 1 LAST VALUE 0.001UF
J 0
(-1975 -275);
DISPLAY 0.978723 (-1975 -275);
FORCEPROP 1 LAST MATERIAL EMPTY
J 0
(-1975 -425);
DISPLAY 0.978723 (-1975 -425);
PAINT RED (-1975 -425);
FORCEPROP 1 LAST PATH I64
J 0
(-1975 -175);
DISPLAY 0.978723 (-1975 -175);
PAINT WHITE (-1975 -175);
DISPLAY INVISIBLE (-1975 -175);
FORCEPROP 2 LAST CDS_LIB pure_quanta
J 0
(-2025 -325);
DISPLAY INVISIBLE (-2025 -325);
FORCEPROP 1 LAST LOCATION C153
J 0
(-1975 -225);
DISPLAY 0.978723 (-1975 -225);
FORCEPROP 1 LASTPIN (-2025 -225) $PN 1
J 0
(-2015 -245);
DISPLAY 0.787234 (-2015 -245);
PAINT MONO (-2015 -245);
FORCEPROP 1 LASTPIN (-2025 -425) $PN 2
J 0
(-2015 -445);
DISPLAY 0.787234 (-2015 -445);
PAINT MONO (-2015 -445);
FORCEPROP 0 LAST $SEC 1
J 0
(-1975 -175);
DISPLAY 0.680851 (-1975 -175);
PAINT MONO (-1975 -175);
DISPLAY INVISIBLE (-1975 -175);
FORCEPROP 0 LAST CDS_SEC 1
J 0
(-1975 -175);
DISPLAY 0.680851 (-1975 -175);
DISPLAY INVISIBLE (-1975 -175);
FORCEADD Q_RES..1
(-2000 425);
FORCEPROP 1 LAST PACK_TYPE 0402LF
J 0
(-2050 350);
DISPLAY 0.978723 (-2050 350);
FORCEPROP 1 LAST PART_NUMBER CS00002JB13
J 0
(-2225 525);
DISPLAY 0.978723 (-2225 525);
FORCEPROP 1 LAST TOLERANCE 5%
J 0
(-2400 350);
DISPLAY 0.978723 (-2400 350);
FORCEPROP 1 LAST MATERIAL CHIP
J 0
(-2250 475);
DISPLAY 0.978723 (-2250 475);
FORCEPROP 1 LAST VALUE 0
J 2
(-2150 425);
DISPLAY 0.978723 (-2150 425);
FORCEPROP 1 LAST WATTAGE 1/16W
J 2
(-2075 350);
DISPLAY 0.978723 (-2075 350);
FORCEPROP 2 LAST CDS_LIB pure_quanta
J 0
(-2000 425);
DISPLAY INVISIBLE (-2000 425);
FORCEPROP 1 LAST PATH I65
J 0
(-2050 575);
DISPLAY 0.978723 (-2050 575);
PAINT WHITE (-2050 575);
DISPLAY INVISIBLE (-2050 575);
FORCEPROP 1 LAST LOCATION R382
J 0
(-2050 475);
DISPLAY 0.978723 (-2050 475);
FORCEPROP 1 LASTPIN (-2100 425) $PN 1
J 0
(-2088 437);
DISPLAY 0.787234 (-2088 437);
PAINT MONO (-2088 437);
FORCEPROP 1 LASTPIN (-1900 425) $PN 2
J 0
(-1938 437);
DISPLAY 0.787234 (-1938 437);
PAINT MONO (-1938 437);
FORCEPROP 0 LAST $SEC 1
J 0
(-2050 575);
DISPLAY 0.680851 (-2050 575);
PAINT MONO (-2050 575);
DISPLAY INVISIBLE (-2050 575);
FORCEPROP 0 LAST CDS_SEC 1
J 0
(-2050 575);
DISPLAY 0.680851 (-2050 575);
DISPLAY INVISIBLE (-2050 575);
FORCEADD OFFPAGE..4
R 2
(-3000 425);
FORCEPROP 2 LAST $XR1 35 
J 0
(-3341 425);
DISPLAY 0.638298 (-3341 425);
PAINT MONO (-3341 425);
FORCEPROP 2 LAST $XR0 52 
J 0
(-3251 425);
DISPLAY 0.638298 (-3251 425);
PAINT MONO (-3251 425);
FORCEPROP 2 LAST CDS_LIB standard
J 0
(-3000 425);
DISPLAY INVISIBLE (-3000 425);
FORCEPROP 1 LAST OFFPAGE TRUE
J 2
(-3325 300);
DISPLAY 0.872340 (-3325 300);
PAINT GREEN (-3325 300);
DISPLAY INVISIBLE (-3325 300);
FORCEPROP 1 LAST COMMENT_BODY TRUE
J 2
(-2975 325);
DISPLAY 0.872340 (-2975 325);
PAINT PEACH (-2975 325);
DISPLAY INVISIBLE (-2975 325);
FORCEPROP 2 LAST PATH I66
J 0
(-3200 475);
DISPLAY 0.680851 (-3200 475);
DISPLAY INVISIBLE (-3200 475);
FORCEADD Q_CAP..1
(-1650 1100);
FORCEPROP 1 LAST VOLTAGE 25V
J 0
(-1600 1100);
DISPLAY 0.510638 (-1600 1100);
PAINT SKYBLUE (-1600 1100);
FORCEPROP 1 LAST MATERIAL X6S
J 0
(-1600 1000);
DISPLAY 0.510638 (-1600 1000);
PAINT SKYBLUE (-1600 1000);
FORCEPROP 1 LAST TOLERANCE 10%
J 0
(-1600 1050);
DISPLAY 0.510638 (-1600 1050);
PAINT SKYBLUE (-1600 1050);
FORCEPROP 1 LAST PART_NUMBER CH5104KEB02
J 0
(-1600 950);
DISPLAY 0.510638 (-1600 950);
PAINT WHITE (-1600 950);
FORCEPROP 1 LAST PACK_TYPE C0402
J 0
(-1600 900);
DISPLAY 0.510638 (-1600 900);
PAINT SKYBLUE (-1600 900);
FORCEPROP 1 LAST VALUE 1UF
J 0
(-1600 1150);
DISPLAY 0.510638 (-1600 1150);
PAINT SKYBLUE (-1600 1150);
FORCEPROP 2 LAST CDS_LIB pure_quanta
J 0
(-1650 1100);
DISPLAY INVISIBLE (-1650 1100);
FORCEPROP 1 LAST PATH I67
J 0
(-1600 1250);
DISPLAY 0.978723 (-1600 1250);
PAINT WHITE (-1600 1250);
DISPLAY INVISIBLE (-1600 1250);
FORCEPROP 1 LAST $LOCATION C287
J 0
(-1600 1200);
DISPLAY 0.978723 (-1600 1200);
FORCEPROP 1 LASTPIN (-1650 1200) $PN 1
J 0
(-1640 1180);
DISPLAY 0.787234 (-1640 1180);
PAINT MONO (-1640 1180);
FORCEPROP 1 LASTPIN (-1650 1000) $PN 2
J 0
(-1640 980);
DISPLAY 0.787234 (-1640 980);
PAINT MONO (-1640 980);
FORCEPROP 0 LAST CDS_LOCATION C287
J 0
(-1600 1250);
DISPLAY 0.680851 (-1600 1250);
DISPLAY INVISIBLE (-1600 1250);
FORCEPROP 0 LAST $SEC 1
J 0
(-1600 1250);
DISPLAY 0.680851 (-1600 1250);
PAINT MONO (-1600 1250);
DISPLAY INVISIBLE (-1600 1250);
FORCEPROP 0 LAST CDS_SEC 1
J 0
(-1600 1250);
DISPLAY 0.680851 (-1600 1250);
DISPLAY INVISIBLE (-1600 1250);
FORCEADD Q_RES..2
(-1375 100);
FORCEPROP 1 LAST PACK_TYPE 0402LF
J 0
(-1335 -75);
DISPLAY 0.510638 (-1335 -75);
PAINT SKYBLUE (-1335 -75);
FORCEPROP 1 LAST MATERIAL CHIP
J 0
(-1335 25);
DISPLAY 0.510638 (-1335 25);
PAINT SKYBLUE (-1335 25);
FORCEPROP 1 LAST TOLERANCE 1%
J 0
(-1330 125);
DISPLAY 0.510638 (-1330 125);
PAINT SKYBLUE (-1330 125);
FORCEPROP 1 LAST PART_NUMBER CS31002FB08
J 0
(-1335 -25);
DISPLAY 0.510638 (-1335 -25);
PAINT WHITE (-1335 -25);
FORCEPROP 1 LAST WATTAGE 1/16W
J 0
(-1335 75);
DISPLAY 0.510638 (-1335 75);
PAINT SKYBLUE (-1335 75);
FORCEPROP 1 LAST VALUE 10K
J 0
(-1330 175);
DISPLAY 0.510638 (-1330 175);
PAINT SKYBLUE (-1330 175);
FORCEPROP 1 LAST PATH I68
J 0
(-1325 275);
DISPLAY 0.978723 (-1325 275);
PAINT WHITE (-1325 275);
DISPLAY INVISIBLE (-1325 275);
FORCEPROP 2 LAST CDS_LIB pure_quanta
J 0
(-1375 100);
DISPLAY INVISIBLE (-1375 100);
FORCEPROP 1 LAST $LOCATION R403
J 0
(-1330 225);
DISPLAY 0.978723 (-1330 225);
FORCEPROP 1 LASTPIN (-1375 200) $PN 1
J 0
(-1370 162);
DISPLAY 0.787234 (-1370 162);
PAINT MONO (-1370 162);
FORCEPROP 1 LASTPIN (-1375 0) $PN 2
J 0
(-1370 10);
DISPLAY 0.787234 (-1370 10);
PAINT MONO (-1370 10);
FORCEPROP 0 LAST CDS_LOCATION R403
J 0
(-1325 275);
DISPLAY 0.680851 (-1325 275);
DISPLAY INVISIBLE (-1325 275);
FORCEPROP 0 LAST $SEC 1
J 0
(-1325 275);
DISPLAY 0.680851 (-1325 275);
PAINT MONO (-1325 275);
DISPLAY INVISIBLE (-1325 275);
FORCEPROP 0 LAST CDS_SEC 1
J 0
(-1325 275);
DISPLAY 0.680851 (-1325 275);
DISPLAY INVISIBLE (-1325 275);
FORCEADD Q_CAP..1
(1250 250);
FORCEPROP 1 LAST PACK_TYPE C0805
J 0
(1300 50);
DISPLAY 0.510638 (1300 50);
PAINT SKYBLUE (1300 50);
FORCEPROP 1 LAST MATERIAL X6S
J 0
(1300 150);
DISPLAY 0.510638 (1300 150);
PAINT SKYBLUE (1300 150);
FORCEPROP 1 LAST VALUE 10UF
J 0
(1300 300);
DISPLAY 0.510638 (1300 300);
PAINT SKYBLUE (1300 300);
FORCEPROP 1 LAST PART_NUMBER CH6104KEA00
J 0
(1300 100);
DISPLAY 0.510638 (1300 100);
PAINT WHITE (1300 100);
FORCEPROP 1 LAST TOLERANCE 10%
J 0
(1300 200);
DISPLAY 0.510638 (1300 200);
PAINT SKYBLUE (1300 200);
FORCEPROP 1 LAST VOLTAGE 25V
J 0
(1300 250);
DISPLAY 0.510638 (1300 250);
PAINT SKYBLUE (1300 250);
FORCEPROP 1 LAST PATH I69
J 0
(1300 400);
DISPLAY 0.978723 (1300 400);
PAINT WHITE (1300 400);
DISPLAY INVISIBLE (1300 400);
FORCEPROP 2 LAST CDS_LIB pure_quanta
J 0
(1250 250);
DISPLAY INVISIBLE (1250 250);
FORCEPROP 1 LAST $LOCATION C289
J 0
(1300 350);
DISPLAY 0.978723 (1300 350);
FORCEPROP 1 LASTPIN (1250 350) $PN 1
J 0
(1260 330);
DISPLAY 0.787234 (1260 330);
PAINT MONO (1260 330);
FORCEPROP 1 LASTPIN (1250 150) $PN 2
J 0
(1260 130);
DISPLAY 0.787234 (1260 130);
PAINT MONO (1260 130);
FORCEPROP 0 LAST CDS_LOCATION C289
J 0
(1300 400);
DISPLAY 0.680851 (1300 400);
DISPLAY INVISIBLE (1300 400);
FORCEPROP 0 LAST $SEC 1
J 0
(1300 400);
DISPLAY 0.680851 (1300 400);
PAINT MONO (1300 400);
DISPLAY INVISIBLE (1300 400);
FORCEPROP 0 LAST CDS_SEC 1
J 0
(1300 400);
DISPLAY 0.680851 (1300 400);
DISPLAY INVISIBLE (1300 400);
FORCEADD Q_CAP..1
(1900 250);
FORCEPROP 1 LAST PACK_TYPE 0402
J 0
(1950 50);
DISPLAY 0.510638 (1950 50);
PAINT SKYBLUE (1950 50);
FORCEPROP 1 LAST VALUE 0.1UF
J 0
(1950 300);
DISPLAY 0.510638 (1950 300);
PAINT SKYBLUE (1950 300);
FORCEPROP 1 LAST PART_NUMBER CH4104K1B00
J 0
(1950 100);
DISPLAY 0.510638 (1950 100);
PAINT WHITE (1950 100);
FORCEPROP 1 LAST VOLTAGE 25V
J 0
(1950 250);
DISPLAY 0.510638 (1950 250);
PAINT SKYBLUE (1950 250);
FORCEPROP 1 LAST TOLERANCE 10%
J 0
(1950 200);
DISPLAY 0.510638 (1950 200);
PAINT SKYBLUE (1950 200);
FORCEPROP 1 LAST MATERIAL X7R
J 0
(1950 150);
DISPLAY 0.510638 (1950 150);
PAINT SKYBLUE (1950 150);
FORCEPROP 1 LAST PATH I70
J 0
(1950 400);
DISPLAY 0.978723 (1950 400);
PAINT WHITE (1950 400);
DISPLAY INVISIBLE (1950 400);
FORCEPROP 2 LAST CDS_LIB pure_quanta
J 0
(1900 250);
DISPLAY INVISIBLE (1900 250);
FORCEPROP 1 LAST $LOCATION C291
J 0
(1950 350);
DISPLAY 0.978723 (1950 350);
FORCEPROP 1 LASTPIN (1900 350) $PN 1
J 0
(1910 330);
DISPLAY 0.787234 (1910 330);
PAINT MONO (1910 330);
FORCEPROP 1 LASTPIN (1900 150) $PN 2
J 0
(1910 130);
DISPLAY 0.787234 (1910 130);
PAINT MONO (1910 130);
FORCEPROP 0 LAST CDS_LOCATION C291
J 0
(1950 400);
DISPLAY 0.680851 (1950 400);
DISPLAY INVISIBLE (1950 400);
FORCEPROP 0 LAST $SEC 1
J 0
(1950 400);
DISPLAY 0.680851 (1950 400);
PAINT MONO (1950 400);
DISPLAY INVISIBLE (1950 400);
FORCEPROP 0 LAST CDS_SEC 1
J 0
(1950 400);
DISPLAY 0.680851 (1950 400);
DISPLAY INVISIBLE (1950 400);
FORCEADD Q_CAP..1
(400 1275);
FORCEPROP 1 LAST MATERIAL X6S
J 0
(450 1175);
DISPLAY 0.510638 (450 1175);
PAINT SKYBLUE (450 1175);
FORCEPROP 1 LAST TOLERANCE 10%
J 0
(450 1225);
DISPLAY 0.510638 (450 1225);
PAINT SKYBLUE (450 1225);
FORCEPROP 1 LAST VOLTAGE 25V
J 0
(450 1275);
DISPLAY 0.510638 (450 1275);
PAINT SKYBLUE (450 1275);
FORCEPROP 1 LAST VALUE 10UF
J 0
(450 1325);
DISPLAY 0.510638 (450 1325);
PAINT SKYBLUE (450 1325);
FORCEPROP 1 LAST PACK_TYPE C0805
J 0
(450 1075);
DISPLAY 0.510638 (450 1075);
PAINT SKYBLUE (450 1075);
FORCEPROP 1 LAST PART_NUMBER CH6104KEA00
J 0
(450 1125);
DISPLAY 0.510638 (450 1125);
PAINT WHITE (450 1125);
FORCEPROP 1 LAST PATH I71
J 0
(450 1425);
DISPLAY 0.978723 (450 1425);
PAINT WHITE (450 1425);
DISPLAY INVISIBLE (450 1425);
FORCEPROP 2 LAST CDS_LIB pure_quanta
J 0
(400 1275);
DISPLAY INVISIBLE (400 1275);
FORCEPROP 1 LAST $LOCATION C288
J 0
(450 1375);
DISPLAY 0.978723 (450 1375);
FORCEPROP 1 LASTPIN (400 1375) $PN 1
J 0
(410 1355);
DISPLAY 0.787234 (410 1355);
PAINT MONO (410 1355);
FORCEPROP 1 LASTPIN (400 1175) $PN 2
J 0
(410 1155);
DISPLAY 0.787234 (410 1155);
PAINT MONO (410 1155);
FORCEPROP 0 LAST CDS_LOCATION C288
J 0
(450 1425);
DISPLAY 0.680851 (450 1425);
DISPLAY INVISIBLE (450 1425);
FORCEPROP 0 LAST $SEC 1
J 0
(450 1425);
DISPLAY 0.680851 (450 1425);
PAINT MONO (450 1425);
DISPLAY INVISIBLE (450 1425);
FORCEPROP 0 LAST CDS_SEC 1
J 0
(450 1425);
DISPLAY 0.680851 (450 1425);
DISPLAY INVISIBLE (450 1425);
FORCEADD Q_RES..1
(-3050 75);
FORCEPROP 1 LAST VALUE 0
J 2
(-2825 75);
DISPLAY 0.510638 (-2825 75);
PAINT SKYBLUE (-2825 75);
FORCEPROP 1 LAST MATERIAL EMPTY
J 0
(-2800 75);
DISPLAY 0.510638 (-2800 75);
PAINT RED (-2800 75);
FORCEPROP 1 LAST PART_NUMBER CS00002JB13
J 0
(-3150 125);
DISPLAY 0.510638 (-3150 125);
PAINT WHITE (-3150 125);
FORCEPROP 1 LAST PACK_TYPE 0402LF
J 0
(-3125 25);
DISPLAY 0.510638 (-3125 25);
PAINT SKYBLUE (-3125 25);
FORCEPROP 2 LAST CDS_LIB pure_quanta
J 0
(-3050 75);
DISPLAY INVISIBLE (-3050 75);
FORCEPROP 1 LAST PATH I72
J 0
(-3100 225);
DISPLAY 0.978723 (-3100 225);
PAINT WHITE (-3100 225);
DISPLAY INVISIBLE (-3100 225);
FORCEPROP 1 LAST WATTAGE 1/16W
J 2
(-3075 -75);
DISPLAY 0.510638 (-3075 -75);
PAINT SKYBLUE (-3075 -75);
DISPLAY INVISIBLE (-3075 -75);
FORCEPROP 1 LAST TOLERANCE 5%
J 0
(-3050 -25);
DISPLAY 0.510638 (-3050 -25);
PAINT SKYBLUE (-3050 -25);
DISPLAY INVISIBLE (-3050 -25);
FORCEPROP 1 LAST $LOCATION R873
J 0
(-3250 75);
DISPLAY 0.702128 (-3250 75);
PAINT YELLOW (-3250 75);
FORCEPROP 1 LASTPIN (-3150 75) $PN 1
J 0
(-3138 87);
DISPLAY 0.787234 (-3138 87);
PAINT MONO (-3138 87);
FORCEPROP 1 LASTPIN (-2950 75) $PN 2
J 0
(-2988 87);
DISPLAY 0.787234 (-2988 87);
PAINT MONO (-2988 87);
FORCEPROP 0 LAST CDS_LOCATION R873
J 0
(-3150 150);
DISPLAY 0.680851 (-3150 150);
DISPLAY INVISIBLE (-3150 150);
FORCEPROP 0 LAST $SEC 1
J 0
(-3150 150);
DISPLAY 0.680851 (-3150 150);
PAINT MONO (-3150 150);
DISPLAY INVISIBLE (-3150 150);
FORCEPROP 0 LAST CDS_SEC 1
J 0
(-3150 150);
DISPLAY 0.680851 (-3150 150);
DISPLAY INVISIBLE (-3150 150);
FORCEADD OFFPAGE..2
R 2
(-4000 75);
FORCEPROP 2 LAST $XR0 54 
J 0
(-4254 75);
DISPLAY 0.638298 (-4254 75);
PAINT MONO (-4254 75);
FORCEPROP 2 LAST PATH I73
J 0
(-4250 125);
DISPLAY 0.680851 (-4250 125);
DISPLAY INVISIBLE (-4250 125);
FORCEPROP 1 LAST COMMENT_BODY TRUE
J 2
(-3955 -20);
DISPLAY 0.872340 (-3955 -20);
PAINT PEACH (-3955 -20);
DISPLAY INVISIBLE (-3955 -20);
FORCEPROP 1 LAST OFFPAGE TRUE
J 2
(-4325 -50);
DISPLAY 0.872340 (-4325 -50);
PAINT GREEN (-4325 -50);
DISPLAY INVISIBLE (-4325 -50);
FORCEPROP 2 LAST CDS_LIB standard
J 0
(-4000 75);
DISPLAY INVISIBLE (-4000 75);
FORCEADD QUANTA_TITLE_BLOCK_C..1
(4825 -2375);
FORCEPROP 0 LAST CDS_CON_LAST_MODIFIED Fri Aug 25 17:25:49 2023
J 0
(2940 -2360);
DISPLAY INVISIBLE (2940 -2360);
FORCEPROP 2 LAST Q_DEPT 
J 1
(1062 -2326);
DISPLAY 1.957447 (1062 -2326);
PAINT GREEN (1062 -2326);
FORCEPROP 1 LAST CUSTOM_TXT_CDS <CON_LAST_MODIFIED>
J 0
(2940 -2360);
DISPLAY 0.978723 (2940 -2360);
FORCEPROP 2 LAST CUSTOM_TXT_CDS <XR_PAGE_TITLE>
J 0
(-3065 2875);
DISPLAY 0.638298 (-3065 2875);
PAINT PINK (-3065 2875);
DISPLAY INVISIBLE (-3065 2875);
FORCEPROP 1 LAST CUSTOM_TXT_CDS <NAME_2>
J 0
(1650 -2325);
FORCEPROP 1 LAST CUSTOM_TXT_CDS <NAME_1>
J 0
(1650 -2200);
FORCEPROP 1 LAST CUSTOM_TXT_CDS <Q_NUMBER>
J 0
(3422 -2272);
DISPLAY 1.212766 (3422 -2272);
FORCEPROP 1 LAST CUSTOM_TXT_CDS <Q_PROJ>
J 0
(2443 -2273);
DISPLAY 1.212766 (2443 -2273);
FORCEPROP 1 LAST CUSTOM_TXT_CDS <Q_REV>
J 0
(4641 -2272);
DISPLAY 1.212766 (4641 -2272);
FORCEPROP 1 LAST CUSTOM_TXT_CDS <CON_PAGE_NUM> OF <CON_TOTAL_PAGES>
J 0
(4379 -2357);
DISPLAY 0.978723 (4379 -2357);
FORCEPROP 1 LAST Q_TITLE RT9059 - P2V5_AUX
J 0
(-4541 -2349);
DISPLAY 2.446809 (-4541 -2349);
PAINT GREEN (-4541 -2349);
FORCEPROP 2 LAST PAGE_BORDER TRUE
J 0
(-3065 2875);
DISPLAY 0.638298 (-3065 2875);
PAINT PINK (-3065 2875);
DISPLAY INVISIBLE (-3065 2875);
FORCEPROP 1 LAST CDS_LMAN_SYM_OUTLINE -9475,6775,100,-125
J 0
(4825 -2375);
DISPLAY 0.468085 (4825 -2375);
PAINT GREEN (4825 -2375);
DISPLAY INVISIBLE (4825 -2375);
FORCEPROP 2 LAST CDS_LIB pure_quanta
J 0
(4825 -2375);
DISPLAY INVISIBLE (4825 -2375);
FORCEPROP 1 LAST COMMENT_BODY TRUE
J 0
(4837 -2388);
DISPLAY 0.978723 (4837 -2388);
PAINT PEACH (4837 -2388);
DISPLAY INVISIBLE (4837 -2388);
FORCEPROP 2 LAST CDS_XR_PAGE_TITLE CR-53 : @SCM_LIB.SCM(SCH_1):PAGE53
J 0
(-3065 2875);
DISPLAY 0.638298 (-3065 2875);
PAINT PINK (-3065 2875);
DISPLAY INVISIBLE (-3065 2875);
FORCEADD DNS..2
(-3075 75);
PAINT RED (-3075 75);
FORCEPROP 1 LAST COMMENT_BODY TRUE
R 1
J 0
(-3000 -150);
DISPLAY 0.872340 (-3000 -150);
PAINT PEACH (-3000 -150);
DISPLAY INVISIBLE (-3000 -150);
FORCEPROP 2 LAST CDS_LIB mstr_misc
J 0
(-3075 75);
DISPLAY INVISIBLE (-3075 75);
FORCEADD DNS..2
(-2050 -325);
PAINT RED (-2050 -325);
FORCEPROP 2 LAST CDS_LIB mstr_misc
J 0
(-2050 -325);
DISPLAY INVISIBLE (-2050 -325);
FORCEPROP 1 LAST COMMENT_BODY TRUE
R 1
J 0
(-1975 -550);
DISPLAY 0.872340 (-1975 -550);
PAINT PEACH (-1975 -550);
DISPLAY INVISIBLE (-1975 -550);
FORCEADD CAD_NOTE..1
(-3450 -475);
FORCEPROP 0 LAST L1 THE CAP & DAMPING RS FOR PWRGD SHOULD CLOSE TO DRIVE-END
J 0
(-3500 -675);
DISPLAY 1.021277 (-3500 -675);
PAINT WHITE (-3500 -675);
FORCEPROP 2 LAST CDS_LIB logical_power
J 0
(-3450 -475);
DISPLAY INVISIBLE (-3450 -475);
FORCEPROP 1 LAST COMMENT_BODY TRUE
J 0
(-3425 -375);
DISPLAY 0.978723 (-3425 -375);
PAINT PEACH (-3425 -375);
DISPLAY INVISIBLE (-3425 -375);
WIRE 16 -1 (-1375 200)(-1375 225);
WIRE 16 -1 (-1650 1350)(-1650 1475);
WIRE 16 -1 (-1200 1350)(-1650 1350);
WIRE 16 -1 (-1650 1200)(-1650 1350);
WIRE 16 -1 (400 1650)(400 1425);
WIRE 16 -1 (2400 475)(2400 600);
WIRE 16 -1 (2400 475)(1900 475);
WIRE 16 -1 (-2025 -425)(-2025 -475);
WIRE 16 -1 (400 1000)(400 1175);
WIRE 16 -1 (1250 -125)(1250 -25);
WIRE 16 -1 (-100 -300)(-100 -350);
WIRE 16 -1 (-100 -300)(325 -300);
WIRE 16 -1 (-100 -125)(-100 -300);
WIRE 16 -1 (-1650 825)(-1650 1000);
WIRE 16 -1 (-1050 875)(-1200 875);
WIRE 16 -1 (-1200 875)(-1200 1350);
WIRE 16 -1 (-250 775)(-25 775);
WIRE 16 -1 (-25 775)(-25 825);
WIRE 16 -1 (-250 825)(-25 825);
WIRE 16 -1 (-25 825)(-25 875);
WIRE 16 -1 (-250 875)(-25 875);
WIRE 16 -1 (-25 875)(-25 1425);
WIRE 16 -1 (-25 1425)(400 1425);
WIRE 16 -1 (400 1425)(400 1375);
WIRE 16 -1 (1250 -25)(1250 150);
WIRE 16 -1 (1900 -25)(1250 -25);
WIRE 16 -1 (1900 150)(1900 -25);
WIRE 16 -1 (-250 375)(-25 375);
WIRE 16 -1 (-25 375)(-25 425);
WIRE 16 -1 (-250 425)(-25 425);
WIRE 16 -1 (-25 425)(-25 475);
WIRE 16 -1 (-250 475)(-25 475);
WIRE 16 -1 (-25 475)(325 475);
WIRE 16 -1 (325 350)(325 475);
WIRE 16 -1 (325 475)(1250 475);
WIRE 16 -1 (1250 350)(1250 475);
WIRE 16 -1 (1900 475)(1250 475);
WIRE 16 -1 (1900 475)(1900 350);
WIRE 74 2175 (2750 3675)(4549 3675);
WIRE 74 2175 (4549 3675)(4549 3100);
WIRE 74 2175 (2750 3675)(2750 3100);
WIRE 74 2175 (2750 3100)(4549 3100);
WIRE 16 -1 (-1900 425)(-1050 425);
FORCEPROP 0 LAST SIG_NAME PWRGD_P3V3_AUX_R2
J 0
(-1785 435);
DISPLAY 0.808511 (-1785 435);
WIRE 16 -1 (-1050 -125)(-1375 -125);
WIRE 16 -1 (-1375 0)(-1375 -125);
WIRE 16 -1 (-2025 -125)(-2025 -225);
WIRE 16 -1 (-2025 -125)(-1375 -125);
WIRE 16 -1 (-2425 -125)(-2025 -125);
FORCEPROP 2 LAST SIG_NAME PWRGD_P2V5_AUX_R
J 0
(-2135 -115);
DISPLAY 0.808511 (-2135 -115);
WIRE 16 -1 (-2950 425)(-2100 425);
FORCEPROP 0 LAST SIG_NAME PWRGD_P3V3_AUX
J 0
(-2860 435);
DISPLAY 0.808511 (-2860 435);
WIRE 16 -1 (-2900 -125)(-3950 -125);
FORCEPROP 2 LAST SIG_NAME PWRGD_P2V5_AUX
J 0
(-3935 -115);
DISPLAY 0.808511 (-3935 -115);
WIRE 16 -1 (-2625 -125)(-2900 -125);
WIRE 16 -1 (-2950 75)(-2900 75);
WIRE 16 -1 (-2900 75)(-2900 -125);
WIRE 16 -1 (-3150 75)(-3950 75);
FORCEPROP 2 LAST SIG_NAME PWRGD_P2V5_AUX_R3
J 0
(-3935 85);
DISPLAY 0.808511 (-3935 85);
WIRE 16 -1 (-250 75)(325 75);
FORCEPROP 2 LAST SIG_NAME U39_ADJ
J 0
(-60 85);
DISPLAY 0.808511 (-60 85);
WIRE 16 -1 (325 75)(325 -75);
WIRE 16 -1 (325 75)(325 150);
WIRE 16 2175 (-3275 -1275)(-2150 -1275);
WIRE 16 2175 (-2150 -900)(-2150 -1275);
WIRE 16 2175 (-3275 -900)(-3275 -1275);
WIRE 16 2175 (-3275 -900)(-2150 -900);
WIRE 16 -1 (-250 -125)(-100 -125);
WIRE 16 -1 (325 -275)(325 -300);
DOT 1 (-25 875);
DOT 1 (-2900 -125);
DOT 1 (-1375 -125);
DOT 1 (-25 425);
DOT 1 (325 75);
DOT 1 (-2025 -125);
DOT 1 (-1650 1350);
DOT 1 (1250 -25);
DOT 1 (-25 825);
DOT 1 (-25 475);
DOT 1 (1250 475);
DOT 1 (400 1425);
DOT 1 (-100 -300);
DOT 1 (1900 475);
DOT 1 (325 475);
FORCENOTE
VNOM=0.8(1+RA/RB)=2.5
(75 -625) 0;
DISPLAY LEFT (75 -625);
DISPLAY 1.021277 (75 -625);
PAINT WHITE (75 -625);
FORCENOTE
PD=(3.3-2.5)V*0.15A=0.12W
(2800 3175) 0;
DISPLAY LEFT (2800 3175);
DISPLAY 0.936170 (2800 3175);
PAINT WHITE (2800 3175);
FORCENOTE
OUTPUT RIPPLE<+/-1%
(2800 3400) 0;
DISPLAY LEFT (2800 3400);
DISPLAY 0.936170 (2800 3400);
PAINT WHITE (2800 3400);
FORCENOTE
OUTPUT VOLTAGE=2.5V
(2800 3475) 0;
DISPLAY LEFT (2800 3475);
DISPLAY 1.042553 (2800 3475);
PAINT WHITE (2800 3475);
FORCENOTE
DESIGN SPECIFICATION
(2800 3575) 0;
DISPLAY LEFT (2800 3575);
DISPLAY 1.170213 (2800 3575);
PAINT WHITE (2800 3575);
FORCENOTE
AC<+/-2%
(2800 3250) 0;
DISPLAY LEFT (2800 3250);
DISPLAY 0.936170 (2800 3250);
PAINT WHITE (2800 3250);
FORCENOTE
DC<+/-3%
(2800 3325) 0;
DISPLAY LEFT (2800 3325);
DISPLAY 0.936170 (2800 3325);
PAINT WHITE (2800 3325);
FORCENOTE
P2V5_AUX
(-1195 2376) 0;
DISPLAY LEFT (-1195 2376);
DISPLAY 3.148936 (-1195 2376);
FORCENOTE
IC TABLE
(-3175 -1000) 0;
DISPLAY LEFT (-3175 -1000);
DISPLAY 1.170213 (-3175 -1000);
FORCENOTE
1ST AL009059000
(-3175 -1100) 0;
DISPLAY LEFT (-3175 -1100);
DISPLAY 1.170213 (-3175 -1100);
FORCENOTE
2ND AL009661002
(-3175 -1200) 0;
DISPLAY LEFT (-3175 -1200);
DISPLAY 1.170213 (-3175 -1200);
QUIT
